# T6G (Grand Teton) — schematic netlist excerpt (pin names and nets, part order shuffled) for the footprints in the layout excerpt that follows; sources: Cadence DE-HDL packaged netlist, KiCad conversion of 04192023_DAF0TMB3IC0_F0TG_MB_C_brd_V02_OCP.brd

J19  SCONN288_DDR506112002KQ  IO  pkg DDR288S_1-1VXC  page 89
  VIN_BULK0  = P12V_MEM_CPU0
  RFU0  = NC
  VIN_MGMT  = P3V3_AUX
  HSCL  = I3C_SPD_DDRD_CPU0_SCL
  HSDA  = I3C_SPD_DDRD_CPU0_SDA
  VSS0  = GND
  DQ0_A  = M_D_CPU0_SA_DQ<0>
  VSS1  = GND
  DQ1_A  = M_D_CPU0_SA_DQ<1>
  VSS2  = GND
  DQS0_A_T  = M_D_CPU0_SA_DQS_DP<0>
  DQS0_A_C  = M_D_CPU0_SA_DQS_DN<0>
  VSS3  = GND
  DQ4_A  = M_D_CPU0_SA_DQ<4>
  VSS4  = GND
  DQ5_A  = M_D_CPU0_SA_DQ<5>
  VSS5  = GND
  DQ8_A  = M_D_CPU0_SA_DQ<8>
  VSS6  = GND
  DQ9_A  = M_D_CPU0_SA_DQ<9>
  VSS7  = GND
  DQS1_A_T  = M_D_CPU0_SA_DQS_DP<1>
  DQS1_A_C  = M_D_CPU0_SA_DQS_DN<1>
  VSS8  = GND
  DQ12_A  = M_D_CPU0_SA_DQ<12>
  VSS9  = GND
  DQ13_A  = M_D_CPU0_SA_DQ<13>
  VSS10  = GND
  DQ16_A  = M_D_CPU0_SA_DQ<16>
  VSS11  = GND
  DQ17_A  = M_D_CPU0_SA_DQ<17>
  VSS12  = GND
  DQS2_A_T  = M_D_CPU0_SA_DQS_DP<2>
  DQS2_A_C  = M_D_CPU0_SA_DQS_DN<2>
  VSS13  = GND
  DQ20_A  = M_D_CPU0_SA_DQ<20>
  VSS14  = GND
  DQ21_A  = M_D_CPU0_SA_DQ<21>
  VSS15  = GND
  DQ24_A  = M_D_CPU0_SA_DQ<24>
  VSS16  = GND
  DQ25_A  = M_D_CPU0_SA_DQ<25>
  VSS17  = GND
  DQS3_A_T  = M_D_CPU0_SA_DQS_DP<3>
  DQS3_A_C  = M_D_CPU0_SA_DQS_DN<3>
  VSS18  = GND
  DQ28_A  = M_D_CPU0_SA_DQ<28>
  VSS19  = GND
  DQ29_A  = M_D_CPU0_SA_DQ<29>
  VSS20  = GND
  CB0_A  = M_D_CPU0_SA_CB<0>
  VSS21  = GND
  CB1_A  = M_D_CPU0_SA_CB<1>
  VSS22  = GND
  DQS4_A_T  = M_D_CPU0_SA_DQS_DP<4>
  DQS4_A_C  = M_D_CPU0_SA_DQS_DN<4>
  VSS23  = GND
  CB4_A  = M_D_CPU0_SA_CB<4>
  VSS24  = GND
  CB5_A  = M_D_CPU0_SA_CB<5>
  VSS25  = GND
  ALERT_N  = M_D_CPU0_ALERT_N
  VSS26  = GND
  CS0_A_N  = M_D_CPU0_SA_CS_N<0>
  VSS27  = GND
  CA0_A  = M_D_CPU0_SA_CA<0>
  VSS28  = GND
  CA2_A  = M_D_CPU0_SA_CA<2>
  VSS29  = GND
  CA4_A  = M_D_CPU0_SA_CA<4>
  VSS30  = GND
  CA6_A  = M_D_CPU0_SA_CA<6>
  VSS31  = GND
  PAR_A  = M_D_CPU0_SA_PAR
  VSS32  = GND
  CA0_B  = M_D_CPU0_SB_CA<0>
  VSS33  = GND
  CA2_B  = M_D_CPU0_SB_CA<2>
  VSS34  = GND
  CA4_B  = M_D_CPU0_SB_CA<4>
  VSS35  = GND
  CA6_B  = M_D_CPU0_SB_CA<6>
  VSS36  = GND
  CS0_B_N  = M_D_CPU0_SB_CS_N<0>
  VSS37  = GND
  \lbd||rsp_a_n\  = M_D_CPU0_SA_RSP<0>
  \lbs||rsp_b_n\  = M_D_CPU0_SB_RSP<0>
  VSS38  = GND
  CB4_B  = M_D_CPU0_SB_CB<4>
  VSS39  = GND
  CB5_B  = M_D_CPU0_SB_CB<5>
  VSS40  = GND
  \dqs9_b_t||tdqs9_b_t||dbi4_b_n\  = M_D_CPU0_SB_DQS_DP<9>
  \dqs9_b_c||tdqs9_b_c\  = M_D_CPU0_SB_DQS_DN<9>
  VSS41  = GND
  CB0_B  = M_D_CPU0_SB_CB<0>
  VSS42  = GND
  CB1_B  = M_D_CPU0_SB_CB<1>
  VSS43  = GND
  DQ0_B  = M_D_CPU0_SB_DQ<0>
  VSS44  = GND
  DQ1_B  = M_D_CPU0_SB_DQ<1>
  VSS45  = GND
  DQS0_B_T  = M_D_CPU0_SB_DQS_DP<0>
  DQS0_B_C  = M_D_CPU0_SB_DQS_DN<0>
  VSS46  = GND
  DQ4_B  = M_D_CPU0_SB_DQ<4>
  VSS47  = GND
  DQ5_B  = M_D_CPU0_SB_DQ<5>
  VSS48  = GND
  DQ8_B  = M_D_CPU0_SB_DQ<8>
  VSS49  = GND
  DQ9_B  = M_D_CPU0_SB_DQ<9>
  VSS50  = GND
  DQS1_B_T  = M_D_CPU0_SB_DQS_DP<1>
  DQS1_B_C  = M_D_CPU0_SB_DQS_DN<1>
  VSS51  = GND
  DQ12_B  = M_D_CPU0_SB_DQ<12>
  VSS52  = GND
  DQ13_B  = M_D_CPU0_SB_DQ<13>
  VSS53  = GND
  DQ16_B  = M_D_CPU0_SB_DQ<16>
  VSS54  = GND
  DQ17_B  = M_D_CPU0_SB_DQ<17>
  VSS55  = GND
  DQS2_B_T  = M_D_CPU0_SB_DQS_DP<2>
  DQS2_B_C  = M_D_CPU0_SB_DQS_DN<2>
  VSS56  = GND
  DQ20_B  = M_D_CPU0_SB_DQ<20>
  VSS57  = GND
  DQ21_B  = M_D_CPU0_SB_DQ<21>
  VSS58  = GND
  DQ24_B  = M_D_CPU0_SB_DQ<24>
  VSS59  = GND
  DQ25_B  = M_D_CPU0_SB_DQ<25>
  VSS60  = GND
  DQS3_B_T  = M_D_CPU0_SB_DQS_DP<3>
  DQS3_B_C  = M_D_CPU0_SB_DQS_DN<3>
  VSS61  = GND
  DQ28_B  = M_D_CPU0_SB_DQ<28>
  VSS62  = GND
  DQ29_B  = M_D_CPU0_SB_DQ<29>
  VSS63  = GND
  RFU1  = NC
  VIN_BULK1  = P12V_MEM_CPU0
  VIN_BULK2  = P12V_MEM_CPU0
  \pwr_good||fail_n\  = PWRGD_CHD_CPU0_DIMM
  HAS  = PD_CHD_CPU0_DIMM_SAA
  RFU2  = NC
  RFU3  = NC
  VSS64  = GND
  DQ2_A  = M_D_CPU0_SA_DQ<2>
  VSS65  = GND
  DQ3_A  = M_D_CPU0_SA_DQ<3>
  VSS66  = GND
  \dqs5_a_c||tdqs5_a_c||dqs5_a_t||tdqs5_a_t\  = M_D_CPU0_SA_DQS_DN<5>
  \dqs5_a_t||tdqs5_a_t\  = M_D_CPU0_SA_DQS_DP<5>
  VSS67  = GND
  DQ6_A  = M_D_CPU0_SA_DQ<6>
  VSS68  = GND
  DQ7_A  = M_D_CPU0_SA_DQ<7>
  VSS69  = GND
  DQ10_A  = M_D_CPU0_SA_DQ<10>
  VSS70  = GND
  DQ11_A  = M_D_CPU0_SA_DQ<11>
  VSS71  = GND
  \dqs6_a_c||tdqs6_a_c||dqs6_a_t||tdqs6_a_t\  = M_D_CPU0_SA_DQS_DN<6>
  \dqs6_a_t||tdqs6_a_t\  = M_D_CPU0_SA_DQS_DP<6>
  VSS72  = GND
  DQ14_A  = M_D_CPU0_SA_DQ<14>
  VSS73  = GND
  DQ15_A  = M_D_CPU0_SA_DQ<15>
  VSS74  = GND
  DQ18_A  = M_D_CPU0_SA_DQ<18>
  VSS75  = GND
  DQ19_A  = M_D_CPU0_SA_DQ<19>
  VSS76  = GND
  \dqs7_a_c||tdqs7_a_c\  = M_D_CPU0_SA_DQS_DN<7>
  \dqs7_a_t||tdqs7_a_t\  = M_D_CPU0_SA_DQS_DP<7>
  VSS77  = GND
  DQ22_A  = M_D_CPU0_SA_DQ<22>
  VSS78  = GND
  DQ23_A  = M_D_CPU0_SA_DQ<23>
  VSS79  = GND
  DQ26_A  = M_D_CPU0_SA_DQ<26>
  VSS80  = GND
  DQ27_A  = M_D_CPU0_SA_DQ<27>
  VSS81  = GND
  \dqs8_a_c||tdqs8_a_c\  = M_D_CPU0_SA_DQS_DN<8>
  \dqs8_a_t||tdqs8_a_t\  = M_D_CPU0_SA_DQS_DP<8>
  VSS82  = GND
  DQ30_A  = M_D_CPU0_SA_DQ<30>
  VSS83  = GND
  DQ31_A  = M_D_CPU0_SA_DQ<31>
  VSS84  = GND
  CB2_A  = M_D_CPU0_SA_CB<2>
  VSS85  = GND
  CB3_A  = M_D_CPU0_SA_CB<3>
  VSS86  = GND
  \dqs9_a_c||tdqs9_a_c\  = M_D_CPU0_SA_DQS_DN<9>
  \dqs9_a_t||tdqs9_a_t\  = M_D_CPU0_SA_DQS_DP<9>
  VSS87  = GND
  CB6_A  = M_D_CPU0_SA_CB<6>
  VSS88  = GND
  CB7_A  = M_D_CPU0_SA_CB<7>
  VSS89  = GND
  RESET_N  = M_D_CPU0_RESET_N
  VSS90  = GND
  CS1_A_N  = M_D_CPU0_SA_CS_N<1>
  VSS91  = GND
  CA1_A  = M_D_CPU0_SA_CA<1>
  VSS92  = GND
  CA3_A  = M_D_CPU0_SA_CA<3>
  VSS93  = GND
  CA5_A  = M_D_CPU0_SA_CA<5>
  VSS94  = GND
  CK_T  = M_D_CPU0_CLK_DP<0>
  CK_C  = M_D_CPU0_CLK_DN<0>
  VSS95  = GND
  RFU4  = NC
  CA1_B  = M_D_CPU0_SB_CA<1>
  VSS96  = GND
  CA3_B  = M_D_CPU0_SB_CA<3>
  VSS97  = GND
  CA5_B  = M_D_CPU0_SB_CA<5>
  VSS98  = GND
  PAR_B  = M_D_CPU0_SB_PAR
  VSS99  = GND
  CS1_B_N  = M_D_CPU0_SB_CS_N<1>
  VSS100  = GND
  RFU5  = NC
  RFU6  = NC
  VSS101  = GND
  CB6_B  = M_D_CPU0_SB_CB<6>
  VSS102  = GND
  CB7_B  = M_D_CPU0_SB_CB<7>
  VSS103  = GND
  DQS4_B_C  = M_D_CPU0_SB_DQS_DN<4>
  DQS4_B_T  = M_D_CPU0_SB_DQS_DP<4>
  VSS104  = GND
  CB2_B  = M_D_CPU0_SB_CB<2>
  VSS105  = GND
  CB3_B  = M_D_CPU0_SB_CB<3>
  VSS106  = GND
  DQ2_B  = M_D_CPU0_SB_DQ<2>
  VSS107  = GND
  DQ3_B  = M_D_CPU0_SB_DQ<3>
  VSS108  = GND
  \dqs5_b_c||tdqs5_b_c\  = M_D_CPU0_SB_DQS_DN<5>
  \dqs5_b_t||tdqs5_b_t\  = M_D_CPU0_SB_DQS_DP<5>
  VSS109  = GND
  DQ6_B  = M_D_CPU0_SB_DQ<6>
  VSS110  = GND
  DQ7_B  = M_D_CPU0_SB_DQ<7>
  VSS111  = GND
  DQ10_B  = M_D_CPU0_SB_DQ<10>
  VSS112  = GND
  DQ11_B  = M_D_CPU0_SB_DQ<11>
  VSS113  = GND
  \dqs6_b_c||tdqs6_b_c\  = M_D_CPU0_SB_DQS_DN<6>
  \dqs6_b_t||tdqs6_b_t\  = M_D_CPU0_SB_DQS_DP<6>
  VSS114  = GND
  DQ14_B  = M_D_CPU0_SB_DQ<14>
  VSS115  = GND
  DQ15_B  = M_D_CPU0_SB_DQ<15>
  VSS116  = GND
  DQ18_B  = M_D_CPU0_SB_DQ<18>
  VSS117  = GND
  DQ19_B  = M_D_CPU0_SB_DQ<19>
  VSS118  = GND
  \dqs7_b_c||tdqs7_b_c\  = M_D_CPU0_SB_DQS_DN<7>
  \dqs7_b_t||tdqs7_b_t\  = M_D_CPU0_SB_DQS_DP<7>
  VSS119  = GND
  DQ22_B  = M_D_CPU0_SB_DQ<22>
  VSS120  = GND
  DQ23_B  = M_D_CPU0_SB_DQ<23>
  VSS121  = GND
  DQ26_B  = M_D_CPU0_SB_DQ<26>
  VSS122  = GND
  DQ27_B  = M_D_CPU0_SB_DQ<27>
  VSS123  = GND
  \dqs8_b_c||tdqs8_b_c\  = M_D_CPU0_SB_DQS_DN<8>
  \dqs8_b_t||tdqs8_b_t\  = M_D_CPU0_SB_DQS_DP<8>
  VSS124  = GND
  DQ30_B  = M_D_CPU0_SB_DQ<30>
  VSS125  = GND
  DQ31_B  = M_D_CPU0_SB_DQ<31>
  VSS126  = GND
  G1  = GND
  G2  = GND
  G3  = GND

(kicad_pcb
	(version 20260206)
	(generator "pcbnew")
	(generator_version "10.0")
	(general
		(thickness 1.6)
		(legacy_teardrops no)
	)
	(paper "A4")
	(title_block
		(title "04192023_DAF0TMB3IC0_F0TG_MB_C_brd_V02_OCP.brd")
		(comment 1 "Grand Teton / footprint 2350 of 8354 (J19), pads 1-46 of 291")
	)
	(layers
		(0 "F.Cu" signal "TOP")
		(4 "In1.Cu" signal "GND")
		(6 "In2.Cu" signal "IN1")
		(8 "In3.Cu" signal "GND1")
		(10 "In4.Cu" signal "IN2")
		(12 "In5.Cu" signal "GND2")
		(14 "In6.Cu" signal "IN3")
		(16 "In7.Cu" signal "GND3")
		(18 "In8.Cu" signal "VCC")
		(20 "In9.Cu" signal "VCC1")
		(22 "In10.Cu" signal "GND4")
		(24 "In11.Cu" signal "IN4")
		(26 "In12.Cu" signal "GND5")
		(28 "In13.Cu" signal "IN5")
		(30 "In14.Cu" signal "GND6")
		(32 "In15.Cu" signal "IN6")
		(34 "In16.Cu" signal "GND7")
		(2 "B.Cu" signal "BOTTOM")
		(9 "F.Adhes" user "F.Adhesive")
		(11 "B.Adhes" user "B.Adhesive")
		(13 "F.Paste" user "Package Geometry/Pastemask Top")
		(15 "B.Paste" user "Package Geometry/Pastemask Bottom")
		(5 "F.SilkS" user "Ref Des/Silkscreen Top")
		(7 "B.SilkS" user "Ref Des/Silkscreen Bottom")
		(1 "F.Mask" user "Board Geometry/Soldermask Top")
		(3 "B.Mask" user "Board Geometry/Soldermask Bottom")
		(17 "Dwgs.User" user "User.Drawings")
		(19 "Cmts.User" user "User.Comments")
		(21 "Eco1.User" user "User.Eco1")
		(23 "Eco2.User" user "User.Eco2")
		(25 "Edge.Cuts" user "Board Geometry/Outline")
		(27 "Margin" user)
		(31 "F.CrtYd" user "Package Geometry/Place Bound Top")
		(29 "B.CrtYd" user "Package Geometry/Place Bound Bottom")
		(35 "F.Fab" user "Ref Des/Assembly Top")
		(33 "B.Fab" user "Ref Des/Assembly Bottom")
	)
	(footprint ""
		(layer "F.Cu")
		(at 282.685998 -255.560068 180)
		(property "Reference" "J19"
			(at -2.2098 -81.984088 0)
			(unlocked yes)
			(layer "F.SilkS")
			(effects
				(font
					(size 0.7874 0.5842)
					(thickness 0.1524)
				)
			)
		)
		(property "Value" ""
			(at 0 0 180)
			(layer "F.Fab")
			(effects
				(font
					(size 1.27 1.27)
				)
			)
		)
		(duplicate_pad_numbers_are_jumpers no)
		(pad "1" smd rect
			(at -2.050034 -63.324994 90)
			(size 0.519938 1.4986)
			(layers "F.Cu" "F.Mask" "F.Paste")
			(net "P12V_MEM_CPU0")
		)
		(pad "2" smd rect
			(at -2.050034 -62.47511 90)
			(size 0.519938 1.4986)
			(layers "F.Cu" "F.Mask" "F.Paste")
			(net "Net_2291")
		)
		(pad "3" smd rect
			(at -2.050034 -61.624972 90)
			(size 0.519938 1.4986)
			(layers "F.Cu" "F.Mask" "F.Paste")
			(net "P3V3_AUX")
		)
		(pad "4" smd rect
			(at -2.050034 -60.775088 90)
			(size 0.519938 1.4986)
			(layers "F.Cu" "F.Mask" "F.Paste")
			(net "I3C_SPD_DDRD_CPU0_SCL")
		)
		(pad "5" smd rect
			(at -2.050034 -59.92495 90)
			(size 0.519938 1.4986)
			(layers "F.Cu" "F.Mask" "F.Paste")
			(net "I3C_SPD_DDRD_CPU0_SDA")
		)
		(pad "6" smd rect
			(at -2.050034 -59.075066 90)
			(size 0.519938 1.4986)
			(layers "F.Cu" "F.Mask" "F.Paste")
			(net "GND")
		)
		(pad "7" smd rect
			(at -2.050034 -58.224928 90)
			(size 0.519938 1.4986)
			(layers "F.Cu" "F.Mask" "F.Paste")
			(net "M_D_CPU0_SA_DQ<0>")
		)
		(pad "8" smd rect
			(at -2.050034 -57.375044 90)
			(size 0.519938 1.4986)
			(layers "F.Cu" "F.Mask" "F.Paste")
			(net "GND")
		)
		(pad "9" smd rect
			(at -2.050034 -56.524906 90)
			(size 0.519938 1.4986)
			(layers "F.Cu" "F.Mask" "F.Paste")
			(net "M_D_CPU0_SA_DQ<1>")
		)
		(pad "10" smd rect
			(at -2.050034 -55.675022 90)
			(size 0.519938 1.4986)
			(layers "F.Cu" "F.Mask" "F.Paste")
			(net "GND")
		)
		(pad "11" smd rect
			(at -2.050034 -54.824884 90)
			(size 0.519938 1.4986)
			(layers "F.Cu" "F.Mask" "F.Paste")
			(net "M_D_CPU0_SA_DQS_DP<0>")
		)
		(pad "12" smd rect
			(at -2.050034 -53.975 90)
			(size 0.519938 1.4986)
			(layers "F.Cu" "F.Mask" "F.Paste")
			(net "M_D_CPU0_SA_DQS_DN<0>")
		)
		(pad "13" smd rect
			(at -2.050034 -53.125116 90)
			(size 0.519938 1.4986)
			(layers "F.Cu" "F.Mask" "F.Paste")
			(net "GND")
		)
		(pad "14" smd rect
			(at -2.050034 -52.274978 90)
			(size 0.519938 1.4986)
			(layers "F.Cu" "F.Mask" "F.Paste")
			(net "M_D_CPU0_SA_DQ<4>")
		)
		(pad "15" smd rect
			(at -2.050034 -51.425094 90)
			(size 0.519938 1.4986)
			(layers "F.Cu" "F.Mask" "F.Paste")
			(net "GND")
		)
		(pad "16" smd rect
			(at -2.050034 -50.574956 90)
			(size 0.519938 1.4986)
			(layers "F.Cu" "F.Mask" "F.Paste")
			(net "M_D_CPU0_SA_DQ<5>")
		)
		(pad "17" smd rect
			(at -2.050034 -49.725072 90)
			(size 0.519938 1.4986)
			(layers "F.Cu" "F.Mask" "F.Paste")
			(net "GND")
		)
		(pad "18" smd rect
			(at -2.050034 -48.874934 90)
			(size 0.519938 1.4986)
			(layers "F.Cu" "F.Mask" "F.Paste")
			(net "M_D_CPU0_SA_DQ<8>")
		)
		(pad "19" smd rect
			(at -2.050034 -48.02505 90)
			(size 0.519938 1.4986)
			(layers "F.Cu" "F.Mask" "F.Paste")
			(net "GND")
		)
		(pad "20" smd rect
			(at -2.050034 -47.174912 90)
			(size 0.519938 1.4986)
			(layers "F.Cu" "F.Mask" "F.Paste")
			(net "M_D_CPU0_SA_DQ<9>")
		)
		(pad "21" smd rect
			(at -2.050034 -46.325028 90)
			(size 0.519938 1.4986)
			(layers "F.Cu" "F.Mask" "F.Paste")
			(net "GND")
		)
		(pad "22" smd rect
			(at -2.050034 -45.47489 90)
			(size 0.519938 1.4986)
			(layers "F.Cu" "F.Mask" "F.Paste")
			(net "M_D_CPU0_SA_DQS_DP<1>")
		)
		(pad "23" smd rect
			(at -2.050034 -44.625006 90)
			(size 0.519938 1.4986)
			(layers "F.Cu" "F.Mask" "F.Paste")
			(net "M_D_CPU0_SA_DQS_DN<1>")
		)
		(pad "24" smd rect
			(at -2.050034 -43.775122 90)
			(size 0.519938 1.4986)
			(layers "F.Cu" "F.Mask" "F.Paste")
			(net "GND")
		)
		(pad "25" smd rect
			(at -2.050034 -42.924984 90)
			(size 0.519938 1.4986)
			(layers "F.Cu" "F.Mask" "F.Paste")
			(net "M_D_CPU0_SA_DQ<12>")
		)
		(pad "26" smd rect
			(at -2.050034 -42.0751 90)
			(size 0.519938 1.4986)
			(layers "F.Cu" "F.Mask" "F.Paste")
			(net "GND")
		)
		(pad "27" smd rect
			(at -2.050034 -41.224962 90)
			(size 0.519938 1.4986)
			(layers "F.Cu" "F.Mask" "F.Paste")
			(net "M_D_CPU0_SA_DQ<13>")
		)
		(pad "28" smd rect
			(at -2.050034 -40.375078 90)
			(size 0.519938 1.4986)
			(layers "F.Cu" "F.Mask" "F.Paste")
			(net "GND")
		)
		(pad "29" smd rect
			(at -2.050034 -39.52494 90)
			(size 0.519938 1.4986)
			(layers "F.Cu" "F.Mask" "F.Paste")
			(net "M_D_CPU0_SA_DQ<16>")
		)
		(pad "30" smd rect
			(at -2.050034 -38.675056 90)
			(size 0.519938 1.4986)
			(layers "F.Cu" "F.Mask" "F.Paste")
			(net "GND")
		)
		(pad "31" smd rect
			(at -2.050034 -37.824918 90)
			(size 0.519938 1.4986)
			(layers "F.Cu" "F.Mask" "F.Paste")
			(net "M_D_CPU0_SA_DQ<17>")
		)
		(pad "32" smd rect
			(at -2.050034 -36.975034 90)
			(size 0.519938 1.4986)
			(layers "F.Cu" "F.Mask" "F.Paste")
			(net "GND")
		)
		(pad "33" smd rect
			(at -2.050034 -36.124896 90)
			(size 0.519938 1.4986)
			(layers "F.Cu" "F.Mask" "F.Paste")
			(net "M_D_CPU0_SA_DQS_DP<2>")
		)
		(pad "34" smd rect
			(at -2.050034 -35.275012 90)
			(size 0.519938 1.4986)
			(layers "F.Cu" "F.Mask" "F.Paste")
			(net "M_D_CPU0_SA_DQS_DN<2>")
		)
		(pad "35" smd rect
			(at -2.050034 -34.425128 90)
			(size 0.519938 1.4986)
			(layers "F.Cu" "F.Mask" "F.Paste")
			(net "GND")
		)
		(pad "36" smd rect
			(at -2.050034 -33.57499 90)
			(size 0.519938 1.4986)
			(layers "F.Cu" "F.Mask" "F.Paste")
			(net "M_D_CPU0_SA_DQ<20>")
		)
		(pad "37" smd rect
			(at -2.050034 -32.725106 90)
			(size 0.519938 1.4986)
			(layers "F.Cu" "F.Mask" "F.Paste")
			(net "GND")
		)
		(pad "38" smd rect
			(at -2.050034 -31.874968 90)
			(size 0.519938 1.4986)
			(layers "F.Cu" "F.Mask" "F.Paste")
			(net "M_D_CPU0_SA_DQ<21>")
		)
		(pad "39" smd rect
			(at -2.050034 -31.025084 90)
			(size 0.519938 1.4986)
			(layers "F.Cu" "F.Mask" "F.Paste")
			(net "GND")
		)
		(pad "40" smd rect
			(at -2.050034 -30.174946 90)
			(size 0.519938 1.4986)
			(layers "F.Cu" "F.Mask" "F.Paste")
			(net "M_D_CPU0_SA_DQ<24>")
		)
		(pad "41" smd rect
			(at -2.050034 -29.325062 90)
			(size 0.519938 1.4986)
			(layers "F.Cu" "F.Mask" "F.Paste")
			(net "GND")
		)
		(pad "42" smd rect
			(at -2.050034 -28.474924 90)
			(size 0.519938 1.4986)
			(layers "F.Cu" "F.Mask" "F.Paste")
			(net "M_D_CPU0_SA_DQ<25>")
		)
		(pad "43" smd rect
			(at -2.050034 -27.62504 90)
			(size 0.519938 1.4986)
			(layers "F.Cu" "F.Mask" "F.Paste")
			(net "GND")
		)
		(pad "44" smd rect
			(at -2.050034 -26.774902 90)
			(size 0.519938 1.4986)
			(layers "F.Cu" "F.Mask" "F.Paste")
			(net "M_D_CPU0_SA_DQS_DP<3>")
		)
		(pad "45" smd rect
			(at -2.050034 -25.925018 90)
			(size 0.519938 1.4986)
			(layers "F.Cu" "F.Mask" "F.Paste")
			(net "M_D_CPU0_SA_DQS_DN<3>")
		)
		(pad "46" smd rect
			(at -2.050034 -25.07488 90)
			(size 0.519938 1.4986)
			(layers "F.Cu" "F.Mask" "F.Paste")
			(net "GND")
		)
	)
)
